(kicad_pcb
	(version 20241229)
	(generator "pcbnew")
	(generator_version "9.0")
	(general
		(thickness 1.294)
		(legacy_teardrops no)
	)
	(paper "A3")
	(title_block
		(title "Kintex 410T devboard")
		(date "2024-04-03")
		(rev "1.1.2")
		(comment 9 "footprints 343-347 of 975")
	)
	(layers
		(0 "F.Cu" mixed)
		(4 "In1.Cu" power)
		(6 "In2.Cu" power)
		(8 "In3.Cu" mixed)
		(10 "In4.Cu" power)
		(12 "In5.Cu" mixed)
		(14 "In6.Cu" power)
		(16 "In7.Cu" mixed)
		(18 "In8.Cu" power)
		(2 "B.Cu" mixed)
		(9 "F.Adhes" user "F.Adhesive")
		(11 "B.Adhes" user "B.Adhesive")
		(13 "F.Paste" user)
		(15 "B.Paste" user)
		(5 "F.SilkS" user "F.Silkscreen")
		(7 "B.SilkS" user "B.Silkscreen")
		(1 "F.Mask" user)
		(3 "B.Mask" user)
		(17 "Dwgs.User" user "User.Drawings")
		(19 "Cmts.User" user "User.Comments")
		(21 "Eco1.User" user "User.Eco1")
		(23 "Eco2.User" user "User.Eco2")
		(25 "Edge.Cuts" user)
		(27 "Margin" user)
		(31 "F.CrtYd" user "F.Courtyard")
		(29 "B.CrtYd" user "B.Courtyard")
		(35 "F.Fab" user)
		(33 "B.Fab" user)
	)
	(footprint "antmicro-footprints:C_0402_1005Metric"
		(layer "F.Cu")
		(at 219.2 139.975 180)
		(descr "Capacitor SMD 0402")
		(tags "capacitor SMD 0402")
		(property "Reference" "C373"
			(at 0.8 -0.375 0)
			(layer "F.SilkS")
			(effects
				(font
					(size 0.7 0.7)
					(thickness 0.15)
				)
				(justify right bottom)
			)
		)
		(property "Value" "C_10u_0402"
			(at 0 1.4 0)
			(layer "F.Fab")
			(effects
				(font
					(size 0.7 0.7)
					(thickness 0.15)
				)
				(justify right bottom)
			)
		)
		(property "Description" "SMD Multilayer Ceramic Capacitor, 10 µF, 6.3 V, 0402 [1005 Metric], ± 20%, X5R, CC Series"
			(at 0 0 180)
			(layer "F.Fab")
			(hide yes)
			(effects
				(font
					(size 1.27 1.27)
					(thickness 0.15)
				)
			)
		)
		(property "Author" "Antmicro"
			(at 438.4 279.95 0)
			(layer "F.Fab")
			(hide yes)
			(effects
				(font
					(size 1 1)
					(thickness 0.15)
				)
			)
		)
		(property "Dielectric" ""
			(at 438.4 279.95 0)
			(layer "F.Fab")
			(hide yes)
			(effects
				(font
					(size 1 1)
					(thickness 0.15)
				)
			)
		)
		(property "License" "Apache-2.0"
			(at 438.4 279.95 0)
			(layer "F.Fab")
			(hide yes)
			(effects
				(font
					(size 1 1)
					(thickness 0.15)
				)
			)
		)
		(property "MPN" "CC0402MRX5R5BB106"
			(at 438.4 279.95 0)
			(layer "F.Fab")
			(hide yes)
			(effects
				(font
					(size 1 1)
					(thickness 0.15)
				)
			)
		)
		(property "Manufacturer" "YAGEO"
			(at 438.4 279.95 0)
			(layer "F.Fab")
			(hide yes)
			(effects
				(font
					(size 1 1)
					(thickness 0.15)
				)
			)
		)
		(property "Val" "10u"
			(at 438.4 279.95 0)
			(layer "F.Fab")
			(hide yes)
			(effects
				(font
					(size 1 1)
					(thickness 0.15)
				)
			)
		)
		(property "Voltage" ""
			(at 438.4 279.95 0)
			(layer "F.Fab")
			(hide yes)
			(effects
				(font
					(size 1 1)
					(thickness 0.15)
				)
			)
		)
		(sheetname "Clocks")
		(sheetfile "clocks.kicad_sch")
		(attr smd)
		(fp_rect
			(start -0.925 -0.47)
			(end 0.925 0.47)
			(stroke
				(width 0.05)
				(type default)
			)
			(fill no)
			(layer "F.CrtYd")
		)
		(fp_line
			(start 0.504 0.248)
			(end -0.494 0.248)
			(stroke
				(width 0.15)
				(type solid)
			)
			(layer "F.Fab")
		)
		(fp_line
			(start 0.504 -0.25)
			(end 0.504 0.248)
			(stroke
				(width 0.15)
				(type solid)
			)
			(layer "F.Fab")
		)
		(fp_line
			(start -0.494 0.248)
			(end -0.494 -0.25)
			(stroke
				(width 0.15)
				(type solid)
			)
			(layer "F.Fab")
		)
		(fp_line
			(start -0.494 -0.25)
			(end 0.504 -0.25)
			(stroke
				(width 0.15)
				(type solid)
			)
			(layer "F.Fab")
		)
		(pad "1" smd roundrect
			(at -0.48 0 180)
			(size 0.59 0.64)
			(layers "F.Cu" "F.Mask" "F.Paste")
			(roundrect_rratio 0.25)
			(net 1 "GND")
			(pintype "passive")
		)
		(pad "2" smd roundrect
			(at 0.48 0 180)
			(size 0.59 0.64)
			(layers "F.Cu" "F.Mask" "F.Paste")
			(roundrect_rratio 0.25)
			(net 24 "+3V3")
			(pintype "passive")
		)
	)
	(footprint "antmicro-footprints:C_0402_1005Metric"
		(layer "F.Cu")
		(at 173.570001 123.970001 180)
		(descr "Capacitor SMD 0402")
		(tags "capacitor SMD 0402")
		(property "Reference" "C306"
			(at -3.729999 -0.329999 0)
			(layer "F.SilkS")
			(effects
				(font
					(size 0.7 0.7)
					(thickness 0.15)
				)
				(justify right bottom)
			)
		)
		(property "Value" "C_100n_0402"
			(at 0 1.4 0)
			(layer "F.Fab")
			(effects
				(font
					(size 0.7 0.7)
					(thickness 0.15)
				)
				(justify right bottom)
			)
		)
		(property "Description" "SMD Multilayer Ceramic Capacitor, 0.1 µF, 50 V, 0402 [1005 Metric], ± 10%, X5R, GRM Series"
			(at 0 0 180)
			(layer "F.Fab")
			(hide yes)
			(effects
				(font
					(size 1.27 1.27)
					(thickness 0.15)
				)
			)
		)
		(property "Author" "Antmicro"
			(at 347.140002 247.940002 0)
			(layer "F.Fab")
			(hide yes)
			(effects
				(font
					(size 1 1)
					(thickness 0.15)
				)
			)
		)
		(property "Dielectric" "X5R"
			(at 347.140002 247.940002 0)
			(layer "F.Fab")
			(hide yes)
			(effects
				(font
					(size 1 1)
					(thickness 0.15)
				)
			)
		)
		(property "License" "Apache-2.0"
			(at 347.140002 247.940002 0)
			(layer "F.Fab")
			(hide yes)
			(effects
				(font
					(size 1 1)
					(thickness 0.15)
				)
			)
		)
		(property "MPN" "GRM155R61H104KE14D"
			(at 347.140002 247.940002 0)
			(layer "F.Fab")
			(hide yes)
			(effects
				(font
					(size 1 1)
					(thickness 0.15)
				)
			)
		)
		(property "Manufacturer" "Murata"
			(at 347.140002 247.940002 0)
			(layer "F.Fab")
			(hide yes)
			(effects
				(font
					(size 1 1)
					(thickness 0.15)
				)
			)
		)
		(property "Val" "100n"
			(at 347.140002 247.940002 0)
			(layer "F.Fab")
			(hide yes)
			(effects
				(font
					(size 1 1)
					(thickness 0.15)
				)
			)
		)
		(property "Voltage" "50V"
			(at 347.140002 247.940002 0)
			(layer "F.Fab")
			(hide yes)
			(effects
				(font
					(size 1 1)
					(thickness 0.15)
				)
			)
		)
		(sheetname "FMC+ HSPC")
		(sheetfile "fmc-hspc.kicad_sch")
		(attr smd)
		(fp_rect
			(start -0.925 -0.47)
			(end 0.925 0.47)
			(stroke
				(width 0.05)
				(type default)
			)
			(fill no)
			(layer "F.CrtYd")
		)
		(fp_line
			(start 0.504 0.248)
			(end -0.494 0.248)
			(stroke
				(width 0.15)
				(type solid)
			)
			(layer "F.Fab")
		)
		(fp_line
			(start 0.504 -0.25)
			(end 0.504 0.248)
			(stroke
				(width 0.15)
				(type solid)
			)
			(layer "F.Fab")
		)
		(fp_line
			(start -0.494 0.248)
			(end -0.494 -0.25)
			(stroke
				(width 0.15)
				(type solid)
			)
			(layer "F.Fab")
		)
		(fp_line
			(start -0.494 -0.25)
			(end 0.504 -0.25)
			(stroke
				(width 0.15)
				(type solid)
			)
			(layer "F.Fab")
		)
		(pad "1" smd roundrect
			(at -0.48 0 180)
			(size 0.59 0.64)
			(layers "F.Cu" "F.Mask" "F.Paste")
			(roundrect_rratio 0.25)
			(net 87 "/FMC+ HSPC/GTX115.TX3_P")
			(pintype "passive")
		)
		(pad "2" smd roundrect
			(at 0.48 0 180)
			(size 0.59 0.64)
			(layers "F.Cu" "F.Mask" "F.Paste")
			(roundrect_rratio 0.25)
			(net 83 "/FMC+ HSPC/GTX_TX4_C_P")
			(pintype "passive")
		)
	)
	(footprint "antmicro-footprints:C_0402_1005Metric"
		(layer "F.Cu")
		(at 201.703752 101.9115)
		(descr "Capacitor SMD 0402")
		(tags "capacitor SMD 0402")
		(property "Reference" "C293"
			(at 4.296248 8.1885 0)
			(layer "F.SilkS")
			(effects
				(font
					(size 0.7 0.7)
					(thickness 0.15)
				)
				(justify left bottom)
			)
		)
		(property "Value" "C_10u_0402"
			(at 0 1.4 0)
			(layer "F.Fab")
			(effects
				(font
					(size 0.7 0.7)
					(thickness 0.15)
				)
				(justify left bottom)
			)
		)
		(property "Description" "SMD Multilayer Ceramic Capacitor, 10 µF, 6.3 V, 0402 [1005 Metric], ± 20%, X5R, CC Series"
			(at 0 0 0)
			(layer "F.Fab")
			(hide yes)
			(effects
				(font
					(size 1.27 1.27)
					(thickness 0.15)
				)
			)
		)
		(property "Author" "Antmicro"
			(at 0 0 0)
			(layer "F.Fab")
			(hide yes)
			(effects
				(font
					(size 1 1)
					(thickness 0.15)
				)
			)
		)
		(property "Dielectric" ""
			(at 0 0 0)
			(layer "F.Fab")
			(hide yes)
			(effects
				(font
					(size 1 1)
					(thickness 0.15)
				)
			)
		)
		(property "License" "Apache-2.0"
			(at 0 0 0)
			(layer "F.Fab")
			(hide yes)
			(effects
				(font
					(size 1 1)
					(thickness 0.15)
				)
			)
		)
		(property "MPN" "CC0402MRX5R5BB106"
			(at 0 0 0)
			(layer "F.Fab")
			(hide yes)
			(effects
				(font
					(size 1 1)
					(thickness 0.15)
				)
			)
		)
		(property "Manufacturer" "YAGEO"
			(at 0 0 0)
			(layer "F.Fab")
			(hide yes)
			(effects
				(font
					(size 1 1)
					(thickness 0.15)
				)
			)
		)
		(property "Val" "10u"
			(at 0 0 0)
			(layer "F.Fab")
			(hide yes)
			(effects
				(font
					(size 1 1)
					(thickness 0.15)
				)
			)
		)
		(property "Voltage" ""
			(at 0 0 0)
			(layer "F.Fab")
			(hide yes)
			(effects
				(font
					(size 1 1)
					(thickness 0.15)
				)
			)
		)
		(sheetname "HDMI + Ethernet")
		(sheetfile "hdmi-ethernet.kicad_sch")
		(attr smd)
		(fp_rect
			(start -0.925 -0.47)
			(end 0.925 0.47)
			(stroke
				(width 0.05)
				(type default)
			)
			(fill no)
			(layer "F.CrtYd")
		)
		(fp_line
			(start -0.494 -0.25)
			(end 0.504 -0.25)
			(stroke
				(width 0.15)
				(type solid)
			)
			(layer "F.Fab")
		)
		(fp_line
			(start -0.494 0.248)
			(end -0.494 -0.25)
			(stroke
				(width 0.15)
				(type solid)
			)
			(layer "F.Fab")
		)
		(fp_line
			(start 0.504 -0.25)
			(end 0.504 0.248)
			(stroke
				(width 0.15)
				(type solid)
			)
			(layer "F.Fab")
		)
		(fp_line
			(start 0.504 0.248)
			(end -0.494 0.248)
			(stroke
				(width 0.15)
				(type solid)
			)
			(layer "F.Fab")
		)
		(pad "1" smd roundrect
			(at -0.48 0)
			(size 0.59 0.64)
			(layers "F.Cu" "F.Mask" "F.Paste")
			(roundrect_rratio 0.25)
			(net 1 "GND")
			(pintype "passive")
		)
		(pad "2" smd roundrect
			(at 0.48 0)
			(size 0.59 0.64)
			(layers "F.Cu" "F.Mask" "F.Paste")
			(roundrect_rratio 0.25)
			(net 728 "/HDMI + Ethernet/GBE_AVDDL{slash}PLL")
			(pintype "passive")
		)
	)
	(footprint "antmicro-footprints:DHVQFN-14-1EP_2.5x3mm"
		(layer "F.Cu")
		(at 239.25 144.7 180)
		(property "Reference" "U23"
			(at -2.6 -0.45 270)
			(layer "F.SilkS")
			(effects
				(font
					(size 0.7 0.7)
					(thickness 0.15)
				)
				(justify left bottom)
			)
		)
		(property "Value" "TXU0304BQAR"
			(at 0 2.898 180)
			(layer "F.Fab")
			(effects
				(font
					(size 0.7 0.7)
					(thickness 0.15)
				)
				(justify left bottom)
			)
		)
		(property "Description" "Logic translator/level shifter"
			(at 0 0 180)
			(layer "F.Fab")
			(hide yes)
			(effects
				(font
					(size 1.27 1.27)
					(thickness 0.15)
				)
			)
		)
		(property "Author" "Antmicro"
			(at 478.5 289.4 0)
			(layer "F.Fab")
			(hide yes)
			(effects
				(font
					(size 1 1)
					(thickness 0.15)
				)
			)
		)
		(property "License" "Apache-2.0"
			(at 478.5 289.4 0)
			(layer "F.Fab")
			(hide yes)
			(effects
				(font
					(size 1 1)
					(thickness 0.15)
				)
			)
		)
		(property "MPN" "TXU0304BQAR"
			(at 478.5 289.4 0)
			(layer "F.Fab")
			(hide yes)
			(effects
				(font
					(size 1 1)
					(thickness 0.15)
				)
			)
		)
		(property "Manufacturer" "Texas Instruments"
			(at 478.5 289.4 0)
			(layer "F.Fab")
			(hide yes)
			(effects
				(font
					(size 1 1)
					(thickness 0.15)
				)
			)
		)
		(sheetname "USB PHY")
		(sheetfile "usb-phy.kicad_sch")
		(attr smd)
		(fp_line
			(start 1.35 1.6)
			(end 1.35 1.249)
			(stroke
				(width 0.15)
				(type solid)
			)
			(layer "F.SilkS")
		)
		(fp_line
			(start 1.35 -1.601)
			(end 1.35 -1.25)
			(stroke
				(width 0.15)
				(type solid)
			)
			(layer "F.SilkS")
		)
		(fp_line
			(start 1.35 -1.601)
			(end 0.494 -1.601)
			(stroke
				(width 0.15)
				(type solid)
			)
			(layer "F.SilkS")
		)
		(fp_line
			(start 0.494 1.6)
			(end 1.35 1.6)
			(stroke
				(width 0.15)
				(type solid)
			)
			(layer "F.SilkS")
		)
		(fp_line
			(start -1.35 -1.601)
			(end -1.35 -1.25)
			(stroke
				(width 0.15)
				(type solid)
			)
			(layer "F.SilkS")
		)
		(fp_line
			(start -1.351 1.6)
			(end -0.5 1.6)
			(stroke
				(width 0.15)
				(type solid)
			)
			(layer "F.SilkS")
		)
		(fp_line
			(start -1.351 1.6)
			(end -1.351 1.249)
			(stroke
				(width 0.15)
				(type solid)
			)
			(layer "F.SilkS")
		)
		(fp_line
			(start -1.351 -1.601)
			(end -0.5 -1.601)
			(stroke
				(width 0.15)
				(type solid)
			)
			(layer "F.SilkS")
		)
		(fp_circle
			(center -0.7 -1.85)
			(end -0.653 -1.85)
			(stroke
				(width 0.15)
				(type solid)
			)
			(fill yes)
			(layer "F.SilkS")
		)
		(fp_rect
			(start -1.85 -2)
			(end 1.8 1.95)
			(stroke
				(width 0.05)
				(type solid)
			)
			(fill no)
			(layer "F.CrtYd")
		)
		(fp_line
			(start 1.249 1.499)
			(end -1.25 1.499)
			(stroke
				(width 0.15)
				(type solid)
			)
			(layer "F.Fab")
		)
		(fp_line
			(start 1.249 -1.5)
			(end 1.249 1.499)
			(stroke
				(width 0.15)
				(type solid)
			)
			(layer "F.Fab")
		)
		(fp_line
			(start -1 -1.5)
			(end 1.249 -1.5)
			(stroke
				(width 0.15)
				(type solid)
			)
			(layer "F.Fab")
		)
		(fp_line
			(start -1.25 1.499)
			(end -1.25 -1.25)
			(stroke
				(width 0.15)
				(type solid)
			)
			(layer "F.Fab")
		)
		(fp_line
			(start -1.25 -1.25)
			(end -1 -1.5)
			(stroke
				(width 0.15)
				(type solid)
			)
			(layer "F.Fab")
		)
		(pad "1" smd oval
			(at -0.25 -1.5 180)
			(size 0.3 0.8)
			(layers "F.Cu" "F.Mask" "F.Paste")
			(net 707 "/USB PHY/FTDI_3V3")
			(pinfunction "VCCA")
			(pintype "power_in")
		)
		(pad "2" smd oval
			(at -1.25 -1 270)
			(size 0.3 0.8)
			(layers "F.Cu" "F.Mask" "F.Paste")
			(net 1023 "/USB PHY/BDBUS0")
			(pinfunction "A1")
			(pintype "input")
		)
		(pad "3" smd oval
			(at -1.25 -0.5 270)
			(size 0.3 0.8)
			(layers "F.Cu" "F.Mask" "F.Paste")
			(net 1024 "/USB PHY/BDBUS1")
			(pinfunction "A2")
			(pintype "input")
		)
		(pad "4" smd oval
			(at -1.25 0 270)
			(size 0.3 0.8)
			(layers "F.Cu" "F.Mask" "F.Paste")
			(net 925 "/USB PHY/BDBUS3")
			(pinfunction "A3")
			(pintype "input")
		)
		(pad "5" smd oval
			(at -1.25 0.494 270)
			(size 0.3 0.8)
			(layers "F.Cu" "F.Mask" "F.Paste")
			(net 1025 "/USB PHY/BDBUS2")
			(pinfunction "A4Y")
			(pintype "output")
		)
		(pad "6" smd oval
			(at -1.25 0.994 270)
			(size 0.3 0.8)
			(layers "F.Cu" "F.Mask" "F.Paste")
			(net 1208 "unconnected-(U23-NC-Pad6)")
			(pinfunction "NC")
			(pintype "no_connect")
		)
		(pad "7" smd oval
			(at -0.25 1.499 180)
			(size 0.3 0.8)
			(layers "F.Cu" "F.Mask" "F.Paste")
			(net 1 "GND")
			(pinfunction "GND")
			(pintype "passive")
		)
		(pad "8" smd oval
			(at 0.244 1.499 180)
			(size 0.3 0.8)
			(layers "F.Cu" "F.Mask" "F.Paste")
			(net 372 "Net-(U23-OE)")
			(pinfunction "OE")
			(pintype "tri_state")
		)
		(pad "9" smd oval
			(at 1.249 0.994 270)
			(size 0.3 0.8)
			(layers "F.Cu" "F.Mask" "F.Paste")
			(net 1229 "unconnected-(U23-NC-Pad9)")
			(pinfunction "NC")
			(pintype "no_connect")
		)
		(pad "10" smd oval
			(at 1.249 0.494 270)
			(size 0.3 0.8)
			(layers "F.Cu" "F.Mask" "F.Paste")
			(net 378 "Net-(U23-B4)")
			(pinfunction "B4")
			(pintype "input")
		)
		(pad "11" smd oval
			(at 1.249 0 270)
			(size 0.3 0.8)
			(layers "F.Cu" "F.Mask" "F.Paste")
			(net 376 "Net-(U23-B3Y)")
			(pinfunction "B3Y")
			(pintype "output")
		)
		(pad "12" smd oval
			(at 1.249 -0.5 270)
			(size 0.3 0.8)
			(layers "F.Cu" "F.Mask" "F.Paste")
			(net 375 "Net-(U23-B2Y)")
			(pinfunction "B2Y")
			(pintype "output")
		)
		(pad "13" smd oval
			(at 1.249 -1 270)
			(size 0.3 0.8)
			(layers "F.Cu" "F.Mask" "F.Paste")
			(net 374 "Net-(U23-B1Y)")
			(pinfunction "B1Y")
			(pintype "output")
		)
		(pad "14" smd oval
			(at 0.244 -1.5 180)
			(size 0.3 0.8)
			(layers "F.Cu" "F.Mask" "F.Paste")
			(net 24 "+3V3")
			(pinfunction "VCCB")
			(pintype "power_in")
		)
		(pad "15" smd rect
			(at 0 0 180)
			(size 1 1.5)
			(layers "F.Cu" "F.Mask" "F.Paste")
			(net 1 "GND")
			(pinfunction "GND")
			(pintype "power_in")
		)
	)
	(footprint "antmicro-footprints:C_0402_1005Metric"
		(layer "F.Cu")
		(at 199.3625 88.3365 -90)
		(descr "Capacitor SMD 0402")
		(tags "capacitor SMD 0402")
		(property "Reference" "C284"
			(at 1.0135 -1.2075 270)
			(layer "F.SilkS")
			(effects
				(font
					(size 0.7 0.7)
					(thickness 0.15)
				)
				(justify left bottom)
			)
		)
		(property "Value" "C_100n_0402"
			(at 0 1.169 270)
			(layer "F.Fab")
			(effects
				(font
					(size 0.7 0.7)
					(thickness 0.15)
				)
				(justify left bottom)
			)
		)
		(property "Description" "SMD Multilayer Ceramic Capacitor, 0.1 µF, 50 V, 0402 [1005 Metric], ± 10%, X5R, GRM Series"
			(at 0 0 270)
			(layer "F.Fab")
			(hide yes)
			(effects
				(font
					(size 1.27 1.27)
					(thickness 0.15)
				)
			)
		)
		(property "Author" "Antmicro"
			(at 111.026 287.699 0)
			(layer "F.Fab")
			(hide yes)
			(effects
				(font
					(size 1 1)
					(thickness 0.15)
				)
			)
		)
		(property "Dielectric" "X5R"
			(at 111.026 287.699 0)
			(layer "F.Fab")
			(hide yes)
			(effects
				(font
					(size 1 1)
					(thickness 0.15)
				)
			)
		)
		(property "License" "Apache-2.0"
			(at 111.026 287.699 0)
			(layer "F.Fab")
			(hide yes)
			(effects
				(font
					(size 1 1)
					(thickness 0.15)
				)
			)
		)
		(property "MPN" "GRM155R61H104KE14D"
			(at 111.026 287.699 0)
			(layer "F.Fab")
			(hide yes)
			(effects
				(font
					(size 1 1)
					(thickness 0.15)
				)
			)
		)
		(property "Manufacturer" "Murata"
			(at 111.026 287.699 0)
			(layer "F.Fab")
			(hide yes)
			(effects
				(font
					(size 1 1)
					(thickness 0.15)
				)
			)
		)
		(property "Val" "100n"
			(at 111.026 287.699 0)
			(layer "F.Fab")
			(hide yes)
			(effects
				(font
					(size 1 1)
					(thickness 0.15)
				)
			)
		)
		(property "Voltage" "50V"
			(at 111.026 287.699 0)
			(layer "F.Fab")
			(hide yes)
			(effects
				(font
					(size 1 1)
					(thickness 0.15)
				)
			)
		)
		(sheetname "HDMI + Ethernet")
		(sheetfile "hdmi-ethernet.kicad_sch")
		(attr smd)
		(fp_rect
			(start -0.925 -0.47)
			(end 0.925 0.47)
			(stroke
				(width 0.05)
				(type default)
			)
			(fill no)
			(layer "F.CrtYd")
		)
		(fp_line
			(start -0.494 0.248)
			(end -0.494 -0.25)
			(stroke
				(width 0.15)
				(type solid)
			)
			(layer "F.Fab")
		)
		(fp_line
			(start 0.504 0.248)
			(end -0.494 0.248)
			(stroke
				(width 0.15)
				(type solid)
			)
			(layer "F.Fab")
		)
		(fp_line
			(start -0.494 -0.25)
			(end 0.504 -0.25)
			(stroke
				(width 0.15)
				(type solid)
			)
			(layer "F.Fab")
		)
		(fp_line
			(start 0.504 -0.25)
			(end 0.504 0.248)
			(stroke
				(width 0.15)
				(type solid)
			)
			(layer "F.Fab")
		)
		(pad "1" smd roundrect
			(at -0.48 0 270)
			(size 0.59 0.64)
			(layers "F.Cu" "F.Mask" "F.Paste")
			(roundrect_rratio 0.25)
			(net 1 "GND")
			(pintype "passive")
		)
		(pad "2" smd roundrect
			(at 0.48 0 270)
			(size 0.59 0.64)
			(layers "F.Cu" "F.Mask" "F.Paste")
			(roundrect_rratio 0.25)
			(net 727 "+1V2")
			(pintype "passive")
		)
	)
)
